(kicad_pcb
	(version 20241229)
	(generator "pcbnew")
	(generator_version "9.0")
	(general
		(thickness 1.294)
		(legacy_teardrops no)
	)
	(paper "A3")
	(title_block
		(title "Kintex 410T devboard")
		(date "2024-04-03")
		(rev "1.1.2")
		(comment 9 "footprints 12-12 of 975")
	)
	(layers
		(0 "F.Cu" mixed)
		(4 "In1.Cu" power)
		(6 "In2.Cu" power)
		(8 "In3.Cu" mixed)
		(10 "In4.Cu" power)
		(12 "In5.Cu" mixed)
		(14 "In6.Cu" power)
		(16 "In7.Cu" mixed)
		(18 "In8.Cu" power)
		(2 "B.Cu" mixed)
		(9 "F.Adhes" user "F.Adhesive")
		(11 "B.Adhes" user "B.Adhesive")
		(13 "F.Paste" user)
		(15 "B.Paste" user)
		(5 "F.SilkS" user "F.Silkscreen")
		(7 "B.SilkS" user "B.Silkscreen")
		(1 "F.Mask" user)
		(3 "B.Mask" user)
		(17 "Dwgs.User" user "User.Drawings")
		(19 "Cmts.User" user "User.Comments")
		(21 "Eco1.User" user "User.Eco1")
		(23 "Eco2.User" user "User.Eco2")
		(25 "Edge.Cuts" user)
		(27 "Margin" user)
		(31 "F.CrtYd" user "F.Courtyard")
		(29 "B.CrtYd" user "B.Courtyard")
		(35 "F.Fab" user)
		(33 "B.Fab" user)
	)
	(footprint "antmicro-footprints:C_0402_1005Metric"
		(layer "F.Cu")
		(at 204.1625 98.9615 90)
		(descr "Capacitor SMD 0402")
		(tags "capacitor SMD 0402")
		(property "Reference" "C265"
			(at -9.0385 6.5375 90)
			(layer "F.SilkS")
			(effects
				(font
					(size 0.7 0.7)
					(thickness 0.15)
				)
				(justify left bottom)
			)
		)
		(property "Value" "C_100n_0402"
			(at 0 1.169 90)
			(layer "F.Fab")
			(effects
				(font
					(size 0.7 0.7)
					(thickness 0.15)
				)
				(justify left bottom)
			)
		)
		(property "Description" "SMD Multilayer Ceramic Capacitor, 0.1 µF, 50 V, 0402 [1005 Metric], ± 10%, X5R, GRM Series"
			(at 0 0 90)
			(layer "F.Fab")
			(hide yes)
			(effects
				(font
					(size 1.27 1.27)
					(thickness 0.15)
				)
			)
		)
		(property "Author" "Antmicro"
			(at 303.124 -105.201 0)
			(layer "F.Fab")
			(hide yes)
			(effects
				(font
					(size 1 1)
					(thickness 0.15)
				)
			)
		)
		(property "Dielectric" "X5R"
			(at 303.124 -105.201 0)
			(layer "F.Fab")
			(hide yes)
			(effects
				(font
					(size 1 1)
					(thickness 0.15)
				)
			)
		)
		(property "License" "Apache-2.0"
			(at 303.124 -105.201 0)
			(layer "F.Fab")
			(hide yes)
			(effects
				(font
					(size 1 1)
					(thickness 0.15)
				)
			)
		)
		(property "MPN" "GRM155R61H104KE14D"
			(at 303.124 -105.201 0)
			(layer "F.Fab")
			(hide yes)
			(effects
				(font
					(size 1 1)
					(thickness 0.15)
				)
			)
		)
		(property "Manufacturer" "Murata"
			(at 303.124 -105.201 0)
			(layer "F.Fab")
			(hide yes)
			(effects
				(font
					(size 1 1)
					(thickness 0.15)
				)
			)
		)
		(property "Val" "100n"
			(at 303.124 -105.201 0)
			(layer "F.Fab")
			(hide yes)
			(effects
				(font
					(size 1 1)
					(thickness 0.15)
				)
			)
		)
		(property "Voltage" "50V"
			(at 303.124 -105.201 0)
			(layer "F.Fab")
			(hide yes)
			(effects
				(font
					(size 1 1)
					(thickness 0.15)
				)
			)
		)
		(sheetname "HDMI + Ethernet")
		(sheetfile "hdmi-ethernet.kicad_sch")
		(attr smd)
		(fp_rect
			(start -0.925 -0.47)
			(end 0.925 0.47)
			(stroke
				(width 0.05)
				(type default)
			)
			(fill no)
			(layer "F.CrtYd")
		)
		(fp_line
			(start 0.504 -0.25)
			(end 0.504 0.248)
			(stroke
				(width 0.15)
				(type solid)
			)
			(layer "F.Fab")
		)
		(fp_line
			(start -0.494 -0.25)
			(end 0.504 -0.25)
			(stroke
				(width 0.15)
				(type solid)
			)
			(layer "F.Fab")
		)
		(fp_line
			(start 0.504 0.248)
			(end -0.494 0.248)
			(stroke
				(width 0.15)
				(type solid)
			)
			(layer "F.Fab")
		)
		(fp_line
			(start -0.494 0.248)
			(end -0.494 -0.25)
			(stroke
				(width 0.15)
				(type solid)
			)
			(layer "F.Fab")
		)
		(pad "1" smd roundrect
			(at -0.48 0 90)
			(size 0.59 0.64)
			(layers "F.Cu" "F.Mask" "F.Paste")
			(roundrect_rratio 0.25)
			(net 1 "GND")
			(pintype "passive")
		)
		(pad "2" smd roundrect
			(at 0.48 0 90)
			(size 0.59 0.64)
			(layers "F.Cu" "F.Mask" "F.Paste")
			(roundrect_rratio 0.25)
			(net 717 "/HDMI + Ethernet/GBE_AVDDH")
			(pintype "passive")
		)
	)
)
